(kicad_pcb
	(version 20260206)
	(generator "pcbnew")
	(generator_version "10.0")
	(general
		(thickness 1.6)
		(legacy_teardrops no)
	)
	(paper "A4")
	(title_block
		(title "netronome-mezz — pcbd0082-001_rev01_jul9_a.brd")
		(comment 1 "Open CloudServer (Microsoft) / footprints 592-592 of 714")
	)
	(layers
		(0 "F.Cu" signal "TOP")
		(4 "In1.Cu" signal "02_GND")
		(6 "In2.Cu" signal "03_SIG")
		(8 "In3.Cu" signal "04_SIG")
		(10 "In4.Cu" signal "05_GND")
		(12 "In5.Cu" signal "06_PWR1")
		(14 "In6.Cu" signal "07_SIG")
		(16 "In7.Cu" signal "08_SIG")
		(18 "In8.Cu" signal "09_GND")
		(2 "B.Cu" signal "BOTTOM")
		(9 "F.Adhes" user "F.Adhesive")
		(11 "B.Adhes" user "B.Adhesive")
		(13 "F.Paste" user "Package Geometry/Pastemask Top")
		(15 "B.Paste" user "Package Geometry/Pastemask Bottom")
		(5 "F.SilkS" user "Ref Des/Silkscreen Top")
		(7 "B.SilkS" user "Ref Des/Silkscreen Bottom")
		(1 "F.Mask" user "Board Geometry/Soldermask Top")
		(3 "B.Mask" user "Board Geometry/Soldermask Bottom")
		(17 "Dwgs.User" user "User.Drawings")
		(19 "Cmts.User" user "User.Comments")
		(21 "Eco1.User" user "User.Eco1")
		(23 "Eco2.User" user "User.Eco2")
		(25 "Edge.Cuts" user "Board Geometry/Outline")
		(27 "Margin" user)
		(31 "F.CrtYd" user "Package Geometry/Place Bound Top")
		(29 "B.CrtYd" user "Package Geometry/Place Bound Bottom")
		(35 "F.Fab" user "Ref Des/Assembly Top")
		(33 "B.Fab" user "Ref Des/Assembly Bottom")
		(45 "User.4" user "COMPVAL_TYPE_BOTTOM")
	)
	(footprint ""
		(layer "B.Cu")
		(at 77.851 27.813 90)
		(property "Reference" "U19"
			(at 5.3975 6.731 0)
			(unlocked yes)
			(layer "B.SilkS")
			(effects
				(font
					(size 1.27 0.9652)
					(thickness 0.1524)
				)
				(justify left mirror)
			)
		)
		(property "Value" ""
			(at 0 0 90)
			(layer "B.Fab")
			(effects
				(font
					(size 1.27 1.27)
				)
				(justify mirror)
			)
		)
		(property "Component Value" "VALUE"
			(at 0.399999 -9.402597 90)
			(unlocked yes)
			(layer "User.4")
			(effects
				(font
					(size 0.254 0.254)
					(thickness 0.000001)
				)
				(justify mirror)
			)
		)
		(property "Device Type" "MEMC0051"
			(at 5.909996 -11.648211 90)
			(unlocked yes)
			(layer "B.Fab")
			(hide yes)
			(effects
				(font
					(size 1.27 0.9652)
					(thickness 0.000001)
				)
				(justify left mirror)
			)
		)
		(duplicate_pad_numbers_are_jumpers no)
		(fp_line
			(start 4.499991 -7.000011)
			(end 4.499991 7.000011)
			(stroke
				(width 0.1524)
				(type default)
			)
			(layer "B.SilkS")
		)
		(fp_line
			(start -4.499991 -7.000011)
			(end 4.499991 -7.000011)
			(stroke
				(width 0.1524)
				(type default)
			)
			(layer "B.SilkS")
		)
		(fp_line
			(start 4.499991 -5.999988)
			(end 3.499993 -7.000011)
			(stroke
				(width 0.1524)
				(type default)
			)
			(layer "B.SilkS")
		)
		(fp_line
			(start 4.499991 7.000011)
			(end -4.499991 7.000011)
			(stroke
				(width 0.1524)
				(type default)
			)
			(layer "B.SilkS")
		)
		(fp_line
			(start -4.499991 7.000011)
			(end -4.499991 -7.000011)
			(stroke
				(width 0.1524)
				(type default)
			)
			(layer "B.SilkS")
		)
		(fp_poly
			(pts
				(xy 7.50001 10.000005) (xy -7.50001 10.000005) (xy -7.50001 -10.000005) (xy 7.50001 -10.000005)
			)
			(stroke
				(width 0)
				(type default)
			)
			(fill no)
			(layer "B.CrtYd")
		)
		(fp_line
			(start 4.499991 -7.000011)
			(end 4.499991 7.000011)
			(stroke
				(width 0.1)
				(type default)
			)
			(layer "B.Fab")
		)
		(fp_line
			(start -4.499991 -7.000011)
			(end 4.499991 -7.000011)
			(stroke
				(width 0.1)
				(type default)
			)
			(layer "B.Fab")
		)
		(fp_line
			(start 4.499991 -5.999988)
			(end 3.499993 -7.000011)
			(stroke
				(width 0.1)
				(type default)
			)
			(layer "B.Fab")
		)
		(fp_line
			(start 4.499991 7.000011)
			(end -4.499991 7.000011)
			(stroke
				(width 0.1)
				(type default)
			)
			(layer "B.Fab")
		)
		(fp_line
			(start -4.499991 7.000011)
			(end -4.499991 -7.000011)
			(stroke
				(width 0.1)
				(type default)
			)
			(layer "B.Fab")
		)
		(fp_text user "1"
			(at 3.14833 -7.366 0)
			(unlocked yes)
			(layer "B.SilkS")
			(effects
				(font
					(size 0.7874 0.5842)
					(thickness 0.127)
				)
				(justify mirror)
			)
		)
		(fp_text user "A"
			(at 5.05333 -5.588 0)
			(unlocked yes)
			(layer "B.SilkS")
			(effects
				(font
					(size 0.7874 0.5842)
					(thickness 0.127)
				)
				(justify mirror)
			)
		)
		(pad "A1" smd circle
			(at 3.199994 -5.999988 270)
			(size 0.3556 0.3556)
			(layers "B.Cu" "B.Mask" "B.Paste")
			(net "DDR_VDDQ")
		)
		(pad "A2" smd circle
			(at 2.399995 -5.999988 270)
			(size 0.3556 0.3556)
			(layers "B.Cu" "B.Mask" "B.Paste")
			(net "_NC_ECC_DQ13")
		)
		(pad "A3" smd circle
			(at 1.599997 -5.999988 270)
			(size 0.3556 0.3556)
			(layers "B.Cu" "B.Mask" "B.Paste")
			(net "_NC_ECC_DQ15")
		)
		(pad "A7" smd circle
			(at -1.599997 -5.999988 270)
			(size 0.3556 0.3556)
			(layers "B.Cu" "B.Mask" "B.Paste")
			(net "_NC_ECC_DQ12")
		)
		(pad "A8" smd circle
			(at -2.399995 -5.999988 270)
			(size 0.3556 0.3556)
			(layers "B.Cu" "B.Mask" "B.Paste")
			(net "DDR_VDDQ")
		)
		(pad "A9" smd circle
			(at -3.199994 -5.999988 270)
			(size 0.3556 0.3556)
			(layers "B.Cu" "B.Mask" "B.Paste")
			(net "GND")
		)
		(pad "B1" smd circle
			(at 3.199994 -5.19999 270)
			(size 0.3556 0.3556)
			(layers "B.Cu" "B.Mask" "B.Paste")
			(net "GND")
		)
		(pad "B2" smd circle
			(at 2.399995 -5.19999 270)
			(size 0.3556 0.3556)
			(layers "B.Cu" "B.Mask" "B.Paste")
			(net "DDR_VDDQ")
		)
		(pad "B3" smd circle
			(at 1.599997 -5.19999 270)
			(size 0.3556 0.3556)
			(layers "B.Cu" "B.Mask" "B.Paste")
			(net "GND")
		)
		(pad "B7" smd circle
			(at -1.599997 -5.19999 270)
			(size 0.3556 0.3556)
			(layers "B.Cu" "B.Mask" "B.Paste")
			(net "12N3293")
		)
		(pad "B8" smd circle
			(at -2.399995 -5.19999 270)
			(size 0.3556 0.3556)
			(layers "B.Cu" "B.Mask" "B.Paste")
			(net "_NC_ECC_DQ14")
		)
		(pad "B9" smd circle
			(at -3.199994 -5.19999 270)
			(size 0.3556 0.3556)
			(layers "B.Cu" "B.Mask" "B.Paste")
			(net "GND")
		)
		(pad "C1" smd circle
			(at 3.199994 -4.399991 270)
			(size 0.3556 0.3556)
			(layers "B.Cu" "B.Mask" "B.Paste")
			(net "DDR_VDDQ")
		)
		(pad "C2" smd circle
			(at 2.399995 -4.399991 270)
			(size 0.3556 0.3556)
			(layers "B.Cu" "B.Mask" "B.Paste")
			(net "_NC_ECC_DQ11")
		)
		(pad "C3" smd circle
			(at 1.599997 -4.399991 270)
			(size 0.3556 0.3556)
			(layers "B.Cu" "B.Mask" "B.Paste")
			(net "_NC_ECC_DQ9")
		)
		(pad "C7" smd circle
			(at -1.599997 -4.399991 270)
			(size 0.3556 0.3556)
			(layers "B.Cu" "B.Mask" "B.Paste")
			(net "12N3294")
		)
		(pad "C8" smd circle
			(at -2.399995 -4.399991 270)
			(size 0.3556 0.3556)
			(layers "B.Cu" "B.Mask" "B.Paste")
			(net "_NC_ECC_DQ10")
		)
		(pad "C9" smd circle
			(at -3.199994 -4.399991 270)
			(size 0.3556 0.3556)
			(layers "B.Cu" "B.Mask" "B.Paste")
			(net "DDR_VDDQ")
		)
		(pad "D1" smd circle
			(at 3.199994 -3.599993 270)
			(size 0.3556 0.3556)
			(layers "B.Cu" "B.Mask" "B.Paste")
			(net "GND")
		)
		(pad "D2" smd circle
			(at 2.399995 -3.599993 270)
			(size 0.3556 0.3556)
			(layers "B.Cu" "B.Mask" "B.Paste")
			(net "DDR_VDDQ")
		)
		(pad "D3" smd circle
			(at 1.599997 -3.599993 270)
			(size 0.3556 0.3556)
			(layers "B.Cu" "B.Mask" "B.Paste")
			(net "12N3291")
		)
		(pad "D7" smd circle
			(at -1.599997 -3.599993 270)
			(size 0.3556 0.3556)
			(layers "B.Cu" "B.Mask" "B.Paste")
			(net "_NC_ECC_DQ8")
		)
		(pad "D8" smd circle
			(at -2.399995 -3.599993 270)
			(size 0.3556 0.3556)
			(layers "B.Cu" "B.Mask" "B.Paste")
			(net "GND")
		)
		(pad "D9" smd circle
			(at -3.199994 -3.599993 270)
			(size 0.3556 0.3556)
			(layers "B.Cu" "B.Mask" "B.Paste")
			(net "DDR_VDDQ")
		)
		(pad "E1" smd circle
			(at 3.199994 -2.799994 270)
			(size 0.3556 0.3556)
			(layers "B.Cu" "B.Mask" "B.Paste")
			(net "GND")
		)
		(pad "E2" smd circle
			(at 2.399995 -2.799994 270)
			(size 0.3556 0.3556)
			(layers "B.Cu" "B.Mask" "B.Paste")
			(net "GND")
		)
		(pad "E3" smd circle
			(at 1.599997 -2.799994 270)
			(size 0.3556 0.3556)
			(layers "B.Cu" "B.Mask" "B.Paste")
			(net "DDR0_32A_CB2")
		)
		(pad "E7" smd circle
			(at -1.599997 -2.799994 270)
			(size 0.3556 0.3556)
			(layers "B.Cu" "B.Mask" "B.Paste")
			(net "DDR0_32A_DM4")
		)
		(pad "E8" smd circle
			(at -2.399995 -2.799994 270)
			(size 0.3556 0.3556)
			(layers "B.Cu" "B.Mask" "B.Paste")
			(net "GND")
		)
		(pad "E9" smd circle
			(at -3.199994 -2.799994 270)
			(size 0.3556 0.3556)
			(layers "B.Cu" "B.Mask" "B.Paste")
			(net "DDR_VDDQ")
		)
		(pad "F1" smd circle
			(at 3.199994 -1.999996 270)
			(size 0.3556 0.3556)
			(layers "B.Cu" "B.Mask" "B.Paste")
			(net "DDR_VDDQ")
		)
		(pad "F2" smd circle
			(at 2.399995 -1.999996 270)
			(size 0.3556 0.3556)
			(layers "B.Cu" "B.Mask" "B.Paste")
			(net "DDR0_32A_CB0")
		)
		(pad "F3" smd circle
			(at 1.599997 -1.999996 270)
			(size 0.3556 0.3556)
			(layers "B.Cu" "B.Mask" "B.Paste")
			(net "DDR0_32A_DQS4_P")
		)
		(pad "F7" smd circle
			(at -1.599997 -1.999996 270)
			(size 0.3556 0.3556)
			(layers "B.Cu" "B.Mask" "B.Paste")
			(net "DDR0_32A_CB5")
		)
		(pad "F8" smd circle
			(at -2.399995 -1.999996 270)
			(size 0.3556 0.3556)
			(layers "B.Cu" "B.Mask" "B.Paste")
			(net "DDR0_32A_CB4")
		)
		(pad "F9" smd circle
			(at -3.199994 -1.999996 270)
			(size 0.3556 0.3556)
			(layers "B.Cu" "B.Mask" "B.Paste")
			(net "GND")
		)
		(pad "G1" smd circle
			(at 3.199994 -1.199998 270)
			(size 0.3556 0.3556)
			(layers "B.Cu" "B.Mask" "B.Paste")
			(net "GND")
		)
		(pad "G2" smd circle
			(at 2.399995 -1.199998 270)
			(size 0.3556 0.3556)
			(layers "B.Cu" "B.Mask" "B.Paste")
			(net "DDR0_32A_CB6")
		)
		(pad "G3" smd circle
			(at 1.599997 -1.199998 270)
			(size 0.3556 0.3556)
			(layers "B.Cu" "B.Mask" "B.Paste")
			(net "DDR0_32A_DQS4_N")
		)
		(pad "G7" smd circle
			(at -1.599997 -1.199998 270)
			(size 0.3556 0.3556)
			(layers "B.Cu" "B.Mask" "B.Paste")
			(net "DDR_VDDQ")
		)
		(pad "G8" smd circle
			(at -2.399995 -1.199998 270)
			(size 0.3556 0.3556)
			(layers "B.Cu" "B.Mask" "B.Paste")
			(net "GND")
		)
		(pad "G9" smd circle
			(at -3.199994 -1.199998 270)
			(size 0.3556 0.3556)
			(layers "B.Cu" "B.Mask" "B.Paste")
			(net "GND")
		)
		(pad "H1" smd circle
			(at 3.199994 -0.399999 270)
			(size 0.3556 0.3556)
			(layers "B.Cu" "B.Mask" "B.Paste")
			(net "DDR0_32A_VREF1B")
		)
		(pad "H2" smd circle
			(at 2.399995 -0.399999 270)
			(size 0.3556 0.3556)
			(layers "B.Cu" "B.Mask" "B.Paste")
			(net "DDR_VDDQ")
		)
		(pad "H3" smd circle
			(at 1.599997 -0.399999 270)
			(size 0.3556 0.3556)
			(layers "B.Cu" "B.Mask" "B.Paste")
			(net "DDR0_32A_CB7")
		)
		(pad "H7" smd circle
			(at -1.599997 -0.399999 270)
			(size 0.3556 0.3556)
			(layers "B.Cu" "B.Mask" "B.Paste")
			(net "DDR0_32A_CB1")
		)
		(pad "H8" smd circle
			(at -2.399995 -0.399999 270)
			(size 0.3556 0.3556)
			(layers "B.Cu" "B.Mask" "B.Paste")
			(net "DDR0_32A_CB3")
		)
		(pad "H9" smd circle
			(at -3.199994 -0.399999 270)
			(size 0.3556 0.3556)
			(layers "B.Cu" "B.Mask" "B.Paste")
			(net "DDR_VDDQ")
		)
		(pad "J1" smd circle
			(at 3.199994 0.399999 270)
			(size 0.3556 0.3556)
			(layers "B.Cu" "B.Mask" "B.Paste")
			(net "Net_90")
		)
		(pad "J2" smd circle
			(at 2.399995 0.399999 270)
			(size 0.3556 0.3556)
			(layers "B.Cu" "B.Mask" "B.Paste")
			(net "GND")
		)
		(pad "J3" smd circle
			(at 1.599997 0.399999 270)
			(size 0.3556 0.3556)
			(layers "B.Cu" "B.Mask" "B.Paste")
			(net "DDR0_32A_RAS_L")
		)
		(pad "J7" smd circle
			(at -1.599997 0.399999 270)
			(size 0.3556 0.3556)
			(layers "B.Cu" "B.Mask" "B.Paste")
			(net "DDR0_32A_CK0_P")
		)
		(pad "J8" smd circle
			(at -2.399995 0.399999 270)
			(size 0.3556 0.3556)
			(layers "B.Cu" "B.Mask" "B.Paste")
			(net "GND")
		)
		(pad "J9" smd circle
			(at -3.199994 0.399999 270)
			(size 0.3556 0.3556)
			(layers "B.Cu" "B.Mask" "B.Paste")
			(net "Net_504")
		)
		(pad "K1" smd circle
			(at 3.199994 1.199998 270)
			(size 0.3556 0.3556)
			(layers "B.Cu" "B.Mask" "B.Paste")
			(net "DDR0_32A_ODT0")
		)
		(pad "K2" smd circle
			(at 2.399995 1.199998 270)
			(size 0.3556 0.3556)
			(layers "B.Cu" "B.Mask" "B.Paste")
			(net "DDR_VDDQ")
		)
		(pad "K3" smd circle
			(at 1.599997 1.199998 270)
			(size 0.3556 0.3556)
			(layers "B.Cu" "B.Mask" "B.Paste")
			(net "DDR0_32A_CAS_L")
		)
		(pad "K7" smd circle
			(at -1.599997 1.199998 270)
			(size 0.3556 0.3556)
			(layers "B.Cu" "B.Mask" "B.Paste")
			(net "DDR0_32A_CK0_N")
		)
		(pad "K8" smd circle
			(at -2.399995 1.199998 270)
			(size 0.3556 0.3556)
			(layers "B.Cu" "B.Mask" "B.Paste")
			(net "DDR_VDDQ")
		)
		(pad "K9" smd circle
			(at -3.199994 1.199998 270)
			(size 0.3556 0.3556)
			(layers "B.Cu" "B.Mask" "B.Paste")
			(net "DDR0_32A_CKE0")
		)
		(pad "L1" smd circle
			(at 3.199994 1.999996 270)
			(size 0.3556 0.3556)
			(layers "B.Cu" "B.Mask" "B.Paste")
			(net "Net_502")
		)
		(pad "L2" smd circle
			(at 2.399995 1.999996 270)
			(size 0.3556 0.3556)
			(layers "B.Cu" "B.Mask" "B.Paste")
			(net "DDR0_32A_CS0_L")
		)
		(pad "L3" smd circle
			(at 1.599997 1.999996 270)
			(size 0.3556 0.3556)
			(layers "B.Cu" "B.Mask" "B.Paste")
			(net "DDR0_32A_WE_L")
		)
		(pad "L7" smd circle
			(at -1.599997 1.999996 270)
			(size 0.3556 0.3556)
			(layers "B.Cu" "B.Mask" "B.Paste")
			(net "DDR0_32A_A10")
		)
		(pad "L8" smd circle
			(at -2.399995 1.999996 270)
			(size 0.3556 0.3556)
			(layers "B.Cu" "B.Mask" "B.Paste")
			(net "12N3220")
		)
		(pad "L9" smd circle
			(at -3.199994 1.999996 270)
			(size 0.3556 0.3556)
			(layers "B.Cu" "B.Mask" "B.Paste")
			(net "Net_505")
		)
		(pad "M1" smd circle
			(at 3.199994 2.799994 270)
			(size 0.3556 0.3556)
			(layers "B.Cu" "B.Mask" "B.Paste")
			(net "GND")
		)
		(pad "M2" smd circle
			(at 2.399995 2.799994 270)
			(size 0.3556 0.3556)
			(layers "B.Cu" "B.Mask" "B.Paste")
			(net "DDR0_32A_BA0")
		)
		(pad "M3" smd circle
			(at 1.599997 2.799994 270)
			(size 0.3556 0.3556)
			(layers "B.Cu" "B.Mask" "B.Paste")
			(net "DDR0_32A_BA2")
		)
		(pad "M7" smd circle
			(at -1.599997 2.799994 270)
			(size 0.3556 0.3556)
			(layers "B.Cu" "B.Mask" "B.Paste")
			(net "Net_503")
		)
		(pad "M8" smd circle
			(at -2.399995 2.799994 270)
			(size 0.3556 0.3556)
			(layers "B.Cu" "B.Mask" "B.Paste")
			(net "DDR0_32A_VREF1B")
		)
		(pad "M9" smd circle
			(at -3.199994 2.799994 270)
			(size 0.3556 0.3556)
			(layers "B.Cu" "B.Mask" "B.Paste")
			(net "GND")
		)
		(pad "N1" smd circle
			(at 3.199994 3.599993 270)
			(size 0.3556 0.3556)
			(layers "B.Cu" "B.Mask" "B.Paste")
			(net "DDR_VDDQ")
		)
		(pad "N2" smd circle
			(at 2.399995 3.599993 270)
			(size 0.3556 0.3556)
			(layers "B.Cu" "B.Mask" "B.Paste")
			(net "DDR0_32A_A3")
		)
		(pad "N3" smd circle
			(at 1.599997 3.599993 270)
			(size 0.3556 0.3556)
			(layers "B.Cu" "B.Mask" "B.Paste")
			(net "DDR0_32A_A0")
		)
		(pad "N7" smd circle
			(at -1.599997 3.599993 270)
			(size 0.3556 0.3556)
			(layers "B.Cu" "B.Mask" "B.Paste")
			(net "DDR0_32A_A12")
		)
		(pad "N8" smd circle
			(at -2.399995 3.599993 270)
			(size 0.3556 0.3556)
			(layers "B.Cu" "B.Mask" "B.Paste")
			(net "DDR0_32A_BA1")
		)
		(pad "N9" smd circle
			(at -3.199994 3.599993 270)
			(size 0.3556 0.3556)
			(layers "B.Cu" "B.Mask" "B.Paste")
			(net "DDR_VDDQ")
		)
		(pad "P1" smd circle
			(at 3.199994 4.399991 270)
			(size 0.3556 0.3556)
			(layers "B.Cu" "B.Mask" "B.Paste")
			(net "GND")
		)
		(pad "P2" smd circle
			(at 2.399995 4.399991 270)
			(size 0.3556 0.3556)
			(layers "B.Cu" "B.Mask" "B.Paste")
			(net "DDR0_32A_A5")
		)
		(pad "P3" smd circle
			(at 1.599997 4.399991 270)
			(size 0.3556 0.3556)
			(layers "B.Cu" "B.Mask" "B.Paste")
			(net "DDR0_32A_A2")
		)
		(pad "P7" smd circle
			(at -1.599997 4.399991 270)
			(size 0.3556 0.3556)
			(layers "B.Cu" "B.Mask" "B.Paste")
			(net "DDR0_32A_A1")
		)
		(pad "P8" smd circle
			(at -2.399995 4.399991 270)
			(size 0.3556 0.3556)
			(layers "B.Cu" "B.Mask" "B.Paste")
			(net "DDR0_32A_A4")
		)
		(pad "P9" smd circle
			(at -3.199994 4.399991 270)
			(size 0.3556 0.3556)
			(layers "B.Cu" "B.Mask" "B.Paste")
			(net "GND")
		)
		(pad "R1" smd circle
			(at 3.199994 5.19999 270)
			(size 0.3556 0.3556)
			(layers "B.Cu" "B.Mask" "B.Paste")
			(net "DDR_VDDQ")
		)
		(pad "R2" smd circle
			(at 2.399995 5.19999 270)
			(size 0.3556 0.3556)
			(layers "B.Cu" "B.Mask" "B.Paste")
			(net "DDR0_32A_A7")
		)
		(pad "R3" smd circle
			(at 1.599997 5.19999 270)
			(size 0.3556 0.3556)
			(layers "B.Cu" "B.Mask" "B.Paste")
			(net "DDR0_32A_A9")
		)
		(pad "R7" smd circle
			(at -1.599997 5.19999 270)
			(size 0.3556 0.3556)
			(layers "B.Cu" "B.Mask" "B.Paste")
			(net "DDR0_32A_A11")
		)
		(pad "R8" smd circle
			(at -2.399995 5.19999 270)
			(size 0.3556 0.3556)
			(layers "B.Cu" "B.Mask" "B.Paste")
			(net "DDR0_32A_A6")
		)
		(pad "R9" smd circle
			(at -3.199994 5.19999 270)
			(size 0.3556 0.3556)
			(layers "B.Cu" "B.Mask" "B.Paste")
			(net "DDR_VDDQ")
		)
		(pad "T1" smd circle
			(at 3.199994 5.999988 270)
			(size 0.3556 0.3556)
			(layers "B.Cu" "B.Mask" "B.Paste")
			(net "GND")
		)
		(pad "T2" smd circle
			(at 2.399995 5.999988 270)
			(size 0.3556 0.3556)
			(layers "B.Cu" "B.Mask" "B.Paste")
			(net "DDR0_32A_DRAMRST_L")
		)
		(pad "T3" smd circle
			(at 1.599997 5.999988 270)
			(size 0.3556 0.3556)
			(layers "B.Cu" "B.Mask" "B.Paste")
			(net "DDR0_32A_A13")
		)
		(pad "T7" smd circle
			(at -1.599997 5.999988 270)
			(size 0.3556 0.3556)
			(layers "B.Cu" "B.Mask" "B.Paste")
			(net "DDR0_32A_A14")
		)
		(pad "T8" smd circle
			(at -2.399995 5.999988 270)
			(size 0.3556 0.3556)
			(layers "B.Cu" "B.Mask" "B.Paste")
			(net "DDR0_32A_A8")
		)
		(pad "T9" smd circle
			(at -3.199994 5.999988 270)
			(size 0.3556 0.3556)
			(layers "B.Cu" "B.Mask" "B.Paste")
			(net "GND")
		)
	)
)
